#ISCELL
  mstr_misc dns *
  *
#ISCELL
  pure_quanta quanta_title_block_c *
  *
#CELL
  pure_quanta lsf0204drutr *
  page141_i117
#ISCELL
  pure_quanta_power universal_gnd *
  page141_i118
#ISCELL
  pure_quanta_power universal_power *
  page141_i120
#ISCELL
  standard offpage *
  page141_i123
#ISCELL
  standard offpage *
  page141_i126
#ISCELL
  pure_quanta_power universal_power *
  page141_i128
#CELL
  pure_quanta q_res *
  page141_i131
#CELL
  pure_quanta q_cap *
  page141_i133
#ISCELL
  pure_quanta_power universal_gnd *
  page141_i134
#ISCELL
  pure_quanta_power universal_power *
  page141_i135
#ISCELL
  pure_quanta_power universal_gnd *
  page141_i136
#CELL
  pure_quanta q_cap *
  page141_i137
#ISCELL
  standard offpage *
  page141_i138
#ISCELL
  standard offpage *
  page141_i141
#ISCELL
  standard offpage *
  page141_i144
#ISCELL
  pure_quanta_power universal_power *
  page141_i145
#CELL
  pure_quanta q_res *
  page141_i147
#ISCELL
  pure_quanta_power universal_power *
  page141_i148
#ISCELL
  standard offpage *
  page141_i150
#ISCELL
  standard offpage *
  page141_i154
#CELL
  pure_quanta q_res *
  page141_i176
#ISCELL
  standard offpage *
  page141_i177
#ISCELL
  standard offpage *
  page141_i178
#ISCELL
  pure_quanta_power universal_gnd *
  page141_i180
#ISCELL
  pure_quanta_power universal_power *
  page141_i181
#ISCELL
  pure_quanta_power p1v0 *
  page141_i182
#ISCELL
  standard offpage *
  page141_i184
#CELL
  pure_quanta q_res *
  page141_i185
#CELL
  pure_quanta q_res *
  page141_i186
#CELL
  pure_quanta q_cap *
  page141_i187
#ISCELL
  pure_quanta_power universal_gnd *
  page141_i188
#ISCELL
  pure_quanta_power universal_gnd *
  page141_i189
#CELL
  pure_quanta q_cap *
  page141_i190
#CELL
  pure_quanta q_res *
  page141_i192
#ISCELL
  standard offpage *
  page141_i193
#ISCELL
  standard offpage *
  page141_i194
#CELL
  pure_quanta conn4_hfk1040l0p1l7h *
  page141_i195
#CELL
  pure_quanta q_res *
  page141_i196
#CELL
  pure_quanta q_res *
  page141_i197
#CELL
  pure_quanta q_res *
  page141_i198
#CELL
  pure_quanta q_res *
  page141_i199
#ISCELL
  standard offpage *
  page141_i200
#ISCELL
  standard offpage *
  page141_i201
#ISCELL
  standard offpage *
  page141_i202
#CELL
  pure_quanta q_res *
  page141_i203
#CELL
  pure_quanta q_res *
  page141_i204
#CELL
  pure_quanta q_res *
  page141_i205
#CELL
  pure_quanta q_res *
  page141_i206
#ISCELL
  standard offpage *
  page141_i207
#ISCELL
  standard offpage *
  page141_i208
#ISCELL
  standard offpage *
  page141_i209
#ISCELL
  standard offpage *
  page141_i210
#CELL
  pure_quanta q_res *
  page141_i211
#CELL
  pure_quanta q_res *
  page141_i212
#ISCELL
  standard offpage *
  page141_i213
#ISCELL
  standard offpage *
  page141_i88
#CELL
  pure_quanta mosfet_n_gsd *
  page141_i89
#ISCELL
  pure_quanta_power universal_gnd *
  page141_i90
#CELL
  pure_quanta q_res *
  page141_i91
